(kicad_pcb
	(version 20260206)
	(generator "pcbnew")
	(generator_version "10.0")
	(general
		(thickness 1.6)
		(legacy_teardrops no)
	)
	(paper "A4")
	(title_block
		(title "03242023_DA0F0TMBIJ0_F0T_Motherboard_J_brd_V01_OCP.brd")
		(comment 1 "Grand Teton / footprints 1447-1452 of 6105")
	)
	(layers
		(0 "F.Cu" signal "TOP")
		(4 "In1.Cu" signal "GND")
		(6 "In2.Cu" signal "IN1")
		(8 "In3.Cu" signal "GND1")
		(10 "In4.Cu" signal "IN2")
		(12 "In5.Cu" signal "GND2")
		(14 "In6.Cu" signal "IN3")
		(16 "In7.Cu" signal "GND3")
		(18 "In8.Cu" signal "VCC")
		(20 "In9.Cu" signal "VCC1")
		(22 "In10.Cu" signal "GND4")
		(24 "In11.Cu" signal "IN4")
		(26 "In12.Cu" signal "GND5")
		(28 "In13.Cu" signal "IN5")
		(30 "In14.Cu" signal "GND6")
		(32 "In15.Cu" signal "IN6")
		(34 "In16.Cu" signal "GND7")
		(2 "B.Cu" signal "BOTTOM")
		(9 "F.Adhes" user "F.Adhesive")
		(11 "B.Adhes" user "B.Adhesive")
		(13 "F.Paste" user "Package Geometry/Pastemask Top")
		(15 "B.Paste" user "Package Geometry/Pastemask Bottom")
		(5 "F.SilkS" user "Ref Des/Silkscreen Top")
		(7 "B.SilkS" user "Ref Des/Silkscreen Bottom")
		(1 "F.Mask" user "Board Geometry/Soldermask Top")
		(3 "B.Mask" user "Board Geometry/Soldermask Bottom")
		(17 "Dwgs.User" user "User.Drawings")
		(19 "Cmts.User" user "User.Comments")
		(21 "Eco1.User" user "User.Eco1")
		(23 "Eco2.User" user "User.Eco2")
		(25 "Edge.Cuts" user "Board Geometry/Outline")
		(27 "Margin" user)
		(31 "F.CrtYd" user "Package Geometry/Place Bound Top")
		(29 "B.CrtYd" user "Package Geometry/Place Bound Bottom")
		(35 "F.Fab" user "Ref Des/Assembly Top")
		(33 "B.Fab" user "Ref Des/Assembly Bottom")
	)
	(footprint ""
		(layer "F.Cu")
		(at 26.97988 -430.875948)
		(property "Reference" "U256"
			(at -1.9558 -1.97739 0)
			(unlocked yes)
			(layer "F.SilkS")
			(effects
				(font
					(size 0.7874 0.5842)
					(thickness 0.1524)
				)
				(justify left)
			)
		)
		(property "Value" ""
			(at 0 0 0)
			(layer "F.Fab")
			(effects
				(font
					(size 1.27 1.27)
				)
			)
		)
		(duplicate_pad_numbers_are_jumpers no)
		(fp_line
			(start -1.3462 -1.100074)
			(end -0.670052 -1.100074)
			(stroke
				(width 0.1524)
				(type default)
			)
			(layer "F.SilkS")
		)
		(fp_line
			(start -1.3462 1.100074)
			(end -1.3462 -1.100074)
			(stroke
				(width 0.1524)
				(type default)
			)
			(layer "F.SilkS")
		)
		(fp_line
			(start -0.670052 -1.100074)
			(end 0 -0.381)
			(stroke
				(width 0.1524)
				(type default)
			)
			(layer "F.SilkS")
		)
		(fp_line
			(start 0 -0.381)
			(end 0.670052 -1.100074)
			(stroke
				(width 0.1524)
				(type default)
			)
			(layer "F.SilkS")
		)
		(fp_line
			(start 0.670052 -1.100074)
			(end 1.3462 -1.100074)
			(stroke
				(width 0.1524)
				(type default)
			)
			(layer "F.SilkS")
		)
		(fp_line
			(start 1.3462 -1.100074)
			(end 1.3462 1.100074)
			(stroke
				(width 0.1524)
				(type default)
			)
			(layer "F.SilkS")
		)
		(fp_line
			(start 1.3462 1.100074)
			(end -1.3462 1.100074)
			(stroke
				(width 0.1524)
				(type default)
			)
			(layer "F.SilkS")
		)
		(fp_poly
			(pts
				(xy -2.01676 -0.685546) (xy -2.77876 -0.304546) (xy -2.77876 -1.066546)
			)
			(stroke
				(width 0)
				(type default)
			)
			(fill yes)
			(layer "F.SilkS")
		)
		(fp_line
			(start -1.100074 -0.8001)
			(end -0.670052 -0.8001)
			(stroke
				(width 0.1)
				(type default)
			)
			(layer "F.Fab")
		)
		(fp_line
			(start -1.100074 0.8001)
			(end -1.100074 -0.8001)
			(stroke
				(width 0.1)
				(type default)
			)
			(layer "F.Fab")
		)
		(fp_line
			(start -0.670052 -1.100074)
			(end 0.670052 -1.100074)
			(stroke
				(width 0.1)
				(type default)
			)
			(layer "F.Fab")
		)
		(fp_line
			(start -0.670052 -0.8001)
			(end -0.670052 -1.100074)
			(stroke
				(width 0.1)
				(type default)
			)
			(layer "F.Fab")
		)
		(fp_line
			(start -0.670052 0.8001)
			(end -1.100074 0.8001)
			(stroke
				(width 0.1)
				(type default)
			)
			(layer "F.Fab")
		)
		(fp_line
			(start -0.670052 0.8001)
			(end -0.670052 -0.8001)
			(stroke
				(width 0.1)
				(type default)
			)
			(layer "F.Fab")
		)
		(fp_line
			(start -0.670052 1.100074)
			(end -0.670052 0.8001)
			(stroke
				(width 0.1)
				(type default)
			)
			(layer "F.Fab")
		)
		(fp_line
			(start 0.670052 -1.100074)
			(end 0.670052 -0.8001)
			(stroke
				(width 0.1)
				(type default)
			)
			(layer "F.Fab")
		)
		(fp_line
			(start 0.670052 -0.8001)
			(end 0.670052 0.8001)
			(stroke
				(width 0.1)
				(type default)
			)
			(layer "F.Fab")
		)
		(fp_line
			(start 0.670052 -0.8001)
			(end 1.100074 -0.8001)
			(stroke
				(width 0.1)
				(type default)
			)
			(layer "F.Fab")
		)
		(fp_line
			(start 0.670052 0.8001)
			(end 0.670052 1.100074)
			(stroke
				(width 0.1)
				(type default)
			)
			(layer "F.Fab")
		)
		(fp_line
			(start 0.670052 1.100074)
			(end -0.670052 1.100074)
			(stroke
				(width 0.1)
				(type default)
			)
			(layer "F.Fab")
		)
		(fp_line
			(start 1.100074 -0.8001)
			(end 1.100074 0.8001)
			(stroke
				(width 0.1)
				(type default)
			)
			(layer "F.Fab")
		)
		(fp_line
			(start 1.100074 0.8001)
			(end 0.670052 0.8001)
			(stroke
				(width 0.1)
				(type default)
			)
			(layer "F.Fab")
		)
		(fp_poly
			(pts
				(xy -1.524 -0.649986) (xy -2.286 -1.030986) (xy -2.286 -0.268986)
			)
			(stroke
				(width 0)
				(type default)
			)
			(fill yes)
			(layer "F.Fab")
		)
		(pad "1" smd rect
			(at -0.94996 -0.649986 270)
			(size 0.4064 0.508)
			(layers "F.Cu" "F.Mask" "F.Paste")
			(net "RST_PERST_SWB_R_N")
		)
		(pad "2" smd rect
			(at -0.94996 0 270)
			(size 0.4064 0.508)
			(layers "F.Cu" "F.Mask" "F.Paste")
			(net "GND")
		)
		(pad "3" smd rect
			(at -0.94996 0.649986 270)
			(size 0.4064 0.508)
			(layers "F.Cu" "F.Mask" "F.Paste")
			(net "FM_SWB_PWR_EN_R")
		)
		(pad "4" smd rect
			(at 0.94996 0.649986 270)
			(size 0.4064 0.508)
			(layers "F.Cu" "F.Mask" "F.Paste")
			(net "FM_SWB_PWR_EN_R1_BUF")
		)
		(pad "5" smd rect
			(at 0.94996 0 270)
			(size 0.4064 0.508)
			(layers "F.Cu" "F.Mask" "F.Paste")
			(net "P3V3_AUX")
		)
		(pad "6" smd rect
			(at 0.94996 -0.649986 270)
			(size 0.4064 0.508)
			(layers "F.Cu" "F.Mask" "F.Paste")
			(net "RST_PERST_2_SWB_BUF_R_N")
		)
	)
	(footprint ""
		(layer "F.Cu")
		(at 167.064944 -354.6602)
		(property "Reference" "PR701"
			(at 0 0 0)
			(layer "F.SilkS")
			(hide yes)
			(effects
				(font
					(size 1.27 1.27)
				)
			)
		)
		(property "Value" ""
			(at 0 0 0)
			(layer "F.Fab")
			(effects
				(font
					(size 1.27 1.27)
				)
			)
		)
		(duplicate_pad_numbers_are_jumpers no)
		(fp_line
			(start -0.7874 -0.4064)
			(end 0.7874 -0.4064)
			(stroke
				(width 0.1524)
				(type default)
			)
			(layer "F.SilkS")
		)
		(fp_line
			(start -0.7874 0.4064)
			(end -0.7874 -0.4064)
			(stroke
				(width 0.1524)
				(type default)
			)
			(layer "F.SilkS")
		)
		(fp_line
			(start 0.7874 -0.4064)
			(end 0.7874 0.4064)
			(stroke
				(width 0.1524)
				(type default)
			)
			(layer "F.SilkS")
		)
		(fp_line
			(start 0.7874 0.4064)
			(end -0.7874 0.4064)
			(stroke
				(width 0.1524)
				(type default)
			)
			(layer "F.SilkS")
		)
		(fp_line
			(start -0.67945 -0.305054)
			(end -0.12065 -0.305054)
			(stroke
				(width 0.1)
				(type default)
			)
			(layer "F.Fab")
		)
		(fp_line
			(start -0.67945 0.3048)
			(end -0.67945 -0.305054)
			(stroke
				(width 0.1)
				(type default)
			)
			(layer "F.Fab")
		)
		(fp_line
			(start -0.12065 -0.305054)
			(end -0.12065 -0.2794)
			(stroke
				(width 0.1)
				(type default)
			)
			(layer "F.Fab")
		)
		(fp_line
			(start -0.12065 -0.2794)
			(end 0.12065 -0.2794)
			(stroke
				(width 0.1)
				(type default)
			)
			(layer "F.Fab")
		)
		(fp_line
			(start -0.12065 0.2794)
			(end -0.12065 0.3048)
			(stroke
				(width 0.1)
				(type default)
			)
			(layer "F.Fab")
		)
		(fp_line
			(start -0.12065 0.3048)
			(end -0.67945 0.3048)
			(stroke
				(width 0.1)
				(type default)
			)
			(layer "F.Fab")
		)
		(fp_line
			(start 0.120396 0.2794)
			(end -0.12065 0.2794)
			(stroke
				(width 0.1)
				(type default)
			)
			(layer "F.Fab")
		)
		(fp_line
			(start 0.120396 0.3048)
			(end 0.120396 0.2794)
			(stroke
				(width 0.1)
				(type default)
			)
			(layer "F.Fab")
		)
		(fp_line
			(start 0.12065 -0.3048)
			(end 0.67945 -0.3048)
			(stroke
				(width 0.1)
				(type default)
			)
			(layer "F.Fab")
		)
		(fp_line
			(start 0.12065 -0.2794)
			(end 0.12065 -0.3048)
			(stroke
				(width 0.1)
				(type default)
			)
			(layer "F.Fab")
		)
		(fp_line
			(start 0.67945 -0.3048)
			(end 0.67945 0.3048)
			(stroke
				(width 0.1)
				(type default)
			)
			(layer "F.Fab")
		)
		(fp_line
			(start 0.67945 0.3048)
			(end 0.120396 0.3048)
			(stroke
				(width 0.1)
				(type default)
			)
			(layer "F.Fab")
		)
		(pad "1" smd circle
			(at -0.40005 0)
			(size 0 0)
			(layers "F.Cu" "F.Mask" "F.Paste")
			(net "P5V")
		)
		(pad "2" smd circle
			(at 0.40005 0)
			(size 0 0)
			(layers "F.Cu" "F.Mask" "F.Paste")
			(net "PVCCFA_EHV_FIVRA_CPU1_PVCC1")
		)
	)
	(footprint ""
		(layer "F.Cu")
		(at 145.17116 -40.114728 180)
		(property "Reference" "C1877"
			(at 0 0 180)
			(layer "F.SilkS")
			(hide yes)
			(effects
				(font
					(size 1.27 1.27)
				)
			)
		)
		(property "Value" ""
			(at 0 0 180)
			(layer "F.Fab")
			(effects
				(font
					(size 1.27 1.27)
				)
			)
		)
		(duplicate_pad_numbers_are_jumpers no)
		(fp_line
			(start 0.7874 0.4064)
			(end -0.7874 0.4064)
			(stroke
				(width 0.1524)
				(type default)
			)
			(layer "F.SilkS")
		)
		(fp_line
			(start 0.7874 -0.4064)
			(end 0.7874 0.4064)
			(stroke
				(width 0.1524)
				(type default)
			)
			(layer "F.SilkS")
		)
		(fp_line
			(start -0.7874 0.4064)
			(end -0.7874 -0.4064)
			(stroke
				(width 0.1524)
				(type default)
			)
			(layer "F.SilkS")
		)
		(fp_line
			(start -0.7874 -0.4064)
			(end 0.7874 -0.4064)
			(stroke
				(width 0.1524)
				(type default)
			)
			(layer "F.SilkS")
		)
		(fp_line
			(start 0.67945 0.3048)
			(end 0.120396 0.3048)
			(stroke
				(width 0.1)
				(type default)
			)
			(layer "F.Fab")
		)
		(fp_line
			(start 0.67945 -0.3048)
			(end 0.67945 0.3048)
			(stroke
				(width 0.1)
				(type default)
			)
			(layer "F.Fab")
		)
		(fp_line
			(start 0.12065 -0.2794)
			(end 0.12065 -0.3048)
			(stroke
				(width 0.1)
				(type default)
			)
			(layer "F.Fab")
		)
		(fp_line
			(start 0.12065 -0.3048)
			(end 0.67945 -0.3048)
			(stroke
				(width 0.1)
				(type default)
			)
			(layer "F.Fab")
		)
		(fp_line
			(start 0.120396 0.3048)
			(end 0.120396 0.2794)
			(stroke
				(width 0.1)
				(type default)
			)
			(layer "F.Fab")
		)
		(fp_line
			(start 0.120396 0.2794)
			(end -0.12065 0.2794)
			(stroke
				(width 0.1)
				(type default)
			)
			(layer "F.Fab")
		)
		(fp_line
			(start -0.12065 0.3048)
			(end -0.67945 0.3048)
			(stroke
				(width 0.1)
				(type default)
			)
			(layer "F.Fab")
		)
		(fp_line
			(start -0.12065 0.2794)
			(end -0.12065 0.3048)
			(stroke
				(width 0.1)
				(type default)
			)
			(layer "F.Fab")
		)
		(fp_line
			(start -0.12065 -0.2794)
			(end 0.12065 -0.2794)
			(stroke
				(width 0.1)
				(type default)
			)
			(layer "F.Fab")
		)
		(fp_line
			(start -0.12065 -0.305054)
			(end -0.12065 -0.2794)
			(stroke
				(width 0.1)
				(type default)
			)
			(layer "F.Fab")
		)
		(fp_line
			(start -0.67945 0.3048)
			(end -0.67945 -0.305054)
			(stroke
				(width 0.1)
				(type default)
			)
			(layer "F.Fab")
		)
		(fp_line
			(start -0.67945 -0.305054)
			(end -0.12065 -0.305054)
			(stroke
				(width 0.1)
				(type default)
			)
			(layer "F.Fab")
		)
		(pad "1" smd circle
			(at -0.40005 0 180)
			(size 0 0)
			(layers "F.Cu" "F.Mask" "F.Paste")
			(net "P3V3_AUX")
		)
		(pad "2" smd circle
			(at 0.40005 0 180)
			(size 0 0)
			(layers "F.Cu" "F.Mask" "F.Paste")
			(net "GND")
		)
	)
	(footprint ""
		(layer "F.Cu")
		(at 68.093336 -111.65967 180)
		(property "Reference" "R3703"
			(at 0 0 180)
			(layer "F.SilkS")
			(hide yes)
			(effects
				(font
					(size 1.27 1.27)
				)
			)
		)
		(property "Value" ""
			(at 0 0 180)
			(layer "F.Fab")
			(effects
				(font
					(size 1.27 1.27)
				)
			)
		)
		(duplicate_pad_numbers_are_jumpers no)
		(fp_line
			(start 0.7874 0.4064)
			(end -0.7874 0.4064)
			(stroke
				(width 0.1524)
				(type default)
			)
			(layer "F.SilkS")
		)
		(fp_line
			(start 0.7874 -0.4064)
			(end 0.7874 0.4064)
			(stroke
				(width 0.1524)
				(type default)
			)
			(layer "F.SilkS")
		)
		(fp_line
			(start -0.7874 0.4064)
			(end -0.7874 -0.4064)
			(stroke
				(width 0.1524)
				(type default)
			)
			(layer "F.SilkS")
		)
		(fp_line
			(start -0.7874 -0.4064)
			(end 0.7874 -0.4064)
			(stroke
				(width 0.1524)
				(type default)
			)
			(layer "F.SilkS")
		)
		(fp_line
			(start 0.67945 0.3048)
			(end 0.120396 0.3048)
			(stroke
				(width 0.1)
				(type default)
			)
			(layer "F.Fab")
		)
		(fp_line
			(start 0.67945 -0.3048)
			(end 0.67945 0.3048)
			(stroke
				(width 0.1)
				(type default)
			)
			(layer "F.Fab")
		)
		(fp_line
			(start 0.12065 -0.2794)
			(end 0.12065 -0.3048)
			(stroke
				(width 0.1)
				(type default)
			)
			(layer "F.Fab")
		)
		(fp_line
			(start 0.12065 -0.3048)
			(end 0.67945 -0.3048)
			(stroke
				(width 0.1)
				(type default)
			)
			(layer "F.Fab")
		)
		(fp_line
			(start 0.120396 0.3048)
			(end 0.120396 0.2794)
			(stroke
				(width 0.1)
				(type default)
			)
			(layer "F.Fab")
		)
		(fp_line
			(start 0.120396 0.2794)
			(end -0.12065 0.2794)
			(stroke
				(width 0.1)
				(type default)
			)
			(layer "F.Fab")
		)
		(fp_line
			(start -0.12065 0.3048)
			(end -0.67945 0.3048)
			(stroke
				(width 0.1)
				(type default)
			)
			(layer "F.Fab")
		)
		(fp_line
			(start -0.12065 0.2794)
			(end -0.12065 0.3048)
			(stroke
				(width 0.1)
				(type default)
			)
			(layer "F.Fab")
		)
		(fp_line
			(start -0.12065 -0.2794)
			(end 0.12065 -0.2794)
			(stroke
				(width 0.1)
				(type default)
			)
			(layer "F.Fab")
		)
		(fp_line
			(start -0.12065 -0.305054)
			(end -0.12065 -0.2794)
			(stroke
				(width 0.1)
				(type default)
			)
			(layer "F.Fab")
		)
		(fp_line
			(start -0.67945 0.3048)
			(end -0.67945 -0.305054)
			(stroke
				(width 0.1)
				(type default)
			)
			(layer "F.Fab")
		)
		(fp_line
			(start -0.67945 -0.305054)
			(end -0.12065 -0.305054)
			(stroke
				(width 0.1)
				(type default)
			)
			(layer "F.Fab")
		)
		(pad "1" smd circle
			(at -0.40005 0 180)
			(size 0 0)
			(layers "F.Cu" "F.Mask" "F.Paste")
			(net "P3V3_AUX")
		)
		(pad "2" smd circle
			(at 0.40005 0 180)
			(size 0 0)
			(layers "F.Cu" "F.Mask" "F.Paste")
			(net "PCA9548_PCIE0_ADDR2")
		)
	)
	(footprint ""
		(layer "F.Cu")
		(at 10.3124 -401.523708)
		(property "Reference" ""
			(at 0 0 0)
			(layer "F.SilkS")
			(hide yes)
			(effects
				(font
					(size 1.27 1.27)
				)
			)
		)
		(property "Value" ""
			(at 0 0 0)
			(layer "F.Fab")
			(effects
				(font
					(size 1.27 1.27)
				)
			)
		)
		(duplicate_pad_numbers_are_jumpers no)
		(pad "1" smd circle
			(at 0 0)
			(size 0.9906 0.9906)
			(layers "F.Cu" "F.Mask" "F.Paste")
			(net "Net_286")
		)
		(zone
			(layer "F.Cu")
			(hatch none 0.5)
			(connect_pads
				(clearance 0)
			)
			(min_thickness 0.25)
			(keepout
				(tracks not_allowed)
				(vias allowed)
				(pads allowed)
				(copperpour not_allowed)
				(footprints allowed)
			)
			(placement
				(enabled no)
				(sheetname "")
			)
			(fill
				(thermal_gap 0.5)
				(thermal_bridge_width 0.5)
				(island_removal_mode 0)
			)
			(polygon
				(pts
					(arc
						(start 11.938 -401.523708)
						(mid 8.6868 -401.523708)
						(end 11.938 -401.523708)
					)
				)
			)
		)
	)
	(footprint ""
		(layer "F.Cu")
		(at 209.74558 -133.878828 180)
		(property "Reference" "R1745"
			(at 0 0 180)
			(layer "F.SilkS")
			(hide yes)
			(effects
				(font
					(size 1.27 1.27)
				)
			)
		)
		(property "Value" ""
			(at 0 0 180)
			(layer "F.Fab")
			(effects
				(font
					(size 1.27 1.27)
				)
			)
		)
		(duplicate_pad_numbers_are_jumpers no)
		(fp_line
			(start 0.7874 0.4064)
			(end -0.7874 0.4064)
			(stroke
				(width 0.1524)
				(type default)
			)
			(layer "F.SilkS")
		)
		(fp_line
			(start 0.7874 -0.4064)
			(end 0.7874 0.4064)
			(stroke
				(width 0.1524)
				(type default)
			)
			(layer "F.SilkS")
		)
		(fp_line
			(start -0.7874 0.4064)
			(end -0.7874 -0.4064)
			(stroke
				(width 0.1524)
				(type default)
			)
			(layer "F.SilkS")
		)
		(fp_line
			(start -0.7874 -0.4064)
			(end 0.7874 -0.4064)
			(stroke
				(width 0.1524)
				(type default)
			)
			(layer "F.SilkS")
		)
		(fp_line
			(start 0.67945 0.3048)
			(end 0.120396 0.3048)
			(stroke
				(width 0.1)
				(type default)
			)
			(layer "F.Fab")
		)
		(fp_line
			(start 0.67945 -0.3048)
			(end 0.67945 0.3048)
			(stroke
				(width 0.1)
				(type default)
			)
			(layer "F.Fab")
		)
		(fp_line
			(start 0.12065 -0.2794)
			(end 0.12065 -0.3048)
			(stroke
				(width 0.1)
				(type default)
			)
			(layer "F.Fab")
		)
		(fp_line
			(start 0.12065 -0.3048)
			(end 0.67945 -0.3048)
			(stroke
				(width 0.1)
				(type default)
			)
			(layer "F.Fab")
		)
		(fp_line
			(start 0.120396 0.3048)
			(end 0.120396 0.2794)
			(stroke
				(width 0.1)
				(type default)
			)
			(layer "F.Fab")
		)
		(fp_line
			(start 0.120396 0.2794)
			(end -0.12065 0.2794)
			(stroke
				(width 0.1)
				(type default)
			)
			(layer "F.Fab")
		)
		(fp_line
			(start -0.12065 0.3048)
			(end -0.67945 0.3048)
			(stroke
				(width 0.1)
				(type default)
			)
			(layer "F.Fab")
		)
		(fp_line
			(start -0.12065 0.2794)
			(end -0.12065 0.3048)
			(stroke
				(width 0.1)
				(type default)
			)
			(layer "F.Fab")
		)
		(fp_line
			(start -0.12065 -0.2794)
			(end 0.12065 -0.2794)
			(stroke
				(width 0.1)
				(type default)
			)
			(layer "F.Fab")
		)
		(fp_line
			(start -0.12065 -0.305054)
			(end -0.12065 -0.2794)
			(stroke
				(width 0.1)
				(type default)
			)
			(layer "F.Fab")
		)
		(fp_line
			(start -0.67945 0.3048)
			(end -0.67945 -0.305054)
			(stroke
				(width 0.1)
				(type default)
			)
			(layer "F.Fab")
		)
		(fp_line
			(start -0.67945 -0.305054)
			(end -0.12065 -0.305054)
			(stroke
				(width 0.1)
				(type default)
			)
			(layer "F.Fab")
		)
		(pad "1" smd circle
			(at -0.40005 0 180)
			(size 0 0)
			(layers "F.Cu" "F.Mask" "F.Paste")
			(net "FM_COMP_P3V3_AUX_ENIN")
		)
		(pad "2" smd circle
			(at 0.40005 0 180)
			(size 0 0)
			(layers "F.Cu" "F.Mask" "F.Paste")
			(net "FM_PFR_DSW_PWROK_N")
		)
	)
)
